# T6G (Grand Teton) — schematic parts with pin connectivity, parts 8082–8082 of 8303; source: Cadence DE-HDL packaged netlist (pstxprt.dat, pstxnet.dat, pstchip.dat)

U26  GENOA_SP5  SOCKET6096_13568-001 IO  pkg SOCKET6096_93-4X120-45XA  page 37  (pins 4705-5040 of 6096)
  DF32  VSS_DF32  POWER  = GND
  DF33  AGPIO21  BI  = TP_SLOT2_BUF_SKU_ID0
  DF34  \uart0_rts_l||uart2_rxd||agpio137\  BI  = TP_CPU1_UART0_RTS_N
  DF35  VSS_DF35  POWER  = GND
  DF36  \agpio4||sata_act_l\  BI  = NC
  DF37  VSS_DF37  POWER  = GND
  DF39  VSS_DF39  POWER  = GND
  DF40  \agpio5||devslp0||sata_zp0_l\  BI  = IRQ_CPU_BMC_NMI_N
  DF41  TEST4_CCD14  TRI  = NC
  DF42  VSS_DF42  POWER  = GND
  DF43  VSS_DF43  POWER  = GND
  DF44  VSS_DF44  POWER  = GND
  DF45  VSS_DF45  POWER  = GND
  DF46  VSS_DF46  POWER  = GND
  DF47  VSS_DF47  POWER  = GND
  DF48  VSS_DF48  POWER  = GND
  DF49  VSS_DF49  POWER  = GND
  DF50  VSS_DF50  POWER  = GND
  DF51  VSS_DF51  POWER  = GND
  DF52  VSS_DF52  POWER  = GND
  DF53  VSS_DF53  POWER  = GND
  DF54  VSS_DF54  POWER  = GND
  DF55  MCB_DATA31  BI  = M_C_CPU1_SB_DQ<31>
  DF56  VSS_DF56  POWER  = GND
  DF57  VSS_DF57  POWER  = GND
  DF58  VSS_DF58  POWER  = GND
  DF59  VSS_DF59  POWER  = GND
  DF60  MDB_DATA31  BI  = M_D_CPU1_SB_DQ<31>
  DF61  VSS_DF61  POWER  = GND
  DF62  MBB_DATA31  BI  = M_B_CPU1_SB_DQ<31>
  DF63  VSS_DF63  POWER  = GND
  DF64  VSS_DF64  POWER  = GND
  DF65  VSS_DF65  POWER  = GND
  DF66  VSS_DF66  POWER  = GND
  DF67  MFB_DATA31  BI  = M_F_CPU1_SB_DQ<31>
  DF68  VSS_DF68  POWER  = GND
  DF69  MEB_DATA31  BI  = M_E_CPU1_SB_DQ<31>
  DF70  VSS_DF70  POWER  = GND
  DF71  VSS_DF71  POWER  = GND
  DF72  VSS_DF72  POWER  = GND
  DF73  VSS_DF73  POWER  = GND
  DF74  MAB_DATA31  BI  = M_A_CPU1_SB_DQ<31>
  DG1  VSS_DG1  POWER  = GND
  DG2  VSS_DG2  POWER  = GND
  DG3  VDDCR_CPU1_SENSE  POWER  = VSENSE_PVDDCR_CPU1_P1_DP
  DG4  SLP_S5_L  OUT  = CPU1_SLP_S5_N
  DG5  VDD_11_S3_DG5  POWER  = PVDD11_S3_P1
  DG6  VSS_DG6  POWER  = GND
  DG7  VSS_DG7  POWER  = GND
  DG8  VSS_DG8  POWER  = GND
  DG9  VSS_DG9  POWER  = GND
  DG10  RSMRST_L  IN  = RST_CPU1_RSMRST_N
  DG11  AGPIO87  BI  = NC
  DG12  \i2c4_scl||hp_scl||ubm_scl||agpio13\  BI  = NC
  DG13  VSS_DG13  POWER  = GND
  DG14  VSS_DG14  POWER  = GND
  DG15  VSS_DG15  POWER  = GND
  DG16  VSS_DG16  POWER  = GND
  DG17  RSVD_DG17  TRI  = NC
  DG18  VSS_DG18  POWER  = GND
  DG19  VDDCR_CPU1_DG19  POWER  = PVDDCR_CPU1_P1
  DG20  VSS_DG20  POWER  = GND
  DG21  VSS_DG21  POWER  = GND
  DG22  \espi0_dat1||spi0_dat1||agpio121\  BI  = NC
  DG23  \espi_clk1||spi_clk1||agpio75\  BI  = NC
  DG24  VSS_DG24  POWER  = GND
  DG25  \espi1_dat3||spi1_dat3||agpio134\  BI  = NC
  DG26  \spi_cs1_l||agpio119\  BI  = NC
  DG27  VSS_DG27  POWER  = GND
  DG28  \espi_cs0_l||agpio124\  BI  = NC
  DG29  \espi0_dat3||spi0_dat3||agpio123\  BI  = NC
  DG30  VSS_DG30  POWER  = GND
  DG31  AGPIO107  BI  = NC
  DG32  AGPIO109  BI  = NC
  DG33  VSS_DG33  POWER  = GND
  DG34  \uart0_intr||agpio139\  BI  = TP_CPU1_UART0_INTR
  DG35  \uart0_rxd||agpio136\  BI  = TP_CPU1_UART0_RX
  DG36  \pcie_rst1_l||agpio26\  BI  = RST_CPU1_PERST1_N
  DG40  \usb10_oc_l||agpio16\  BI  = NC_CPU1_USB10_OC_N
  DG41  VSS_DG41  POWER  = GND
  DG42  TEST5_CCD14  TRI  = NC
  DG43  VSS_DG43  POWER  = GND
  DG44  P4_RXN3  IN  = P3E_CPU1_P4_RX_DN<3>
  DG45  P4_RXP3  IN  = P3E_CPU1_P4_RX_DP<3>
  DG46  VSS_DG46  POWER  = GND
  DG47  P4_RXN2  IN  = P3E_CPU1_P4_RX_DN<2>
  DG48  P4_RXP2  IN  = P3E_CPU1_P4_RX_DP<2>
  DG49  VSS_DG49  POWER  = GND
  DG50  P4_RXN1  IN  = P3E_CPU1_P4_RX_DN<1>
  DG51  P4_RXP1  IN  = P3E_CPU1_P4_RX_DP<1>
  DG52  VSS_DG52  POWER  = GND
  DG53  P4_RXN0  IN  = P3E_CPU1_P4_RX_DN<0>
  DG54  P4_RXP0  IN  = P3E_CPU1_P4_RX_DP<0>
  DG55  VSS_DG55  POWER  = GND
  DG56  VSS_DG56  POWER  = GND
  DG57  VDDCR_CPU1_DG57  POWER  = PVDDCR_CPU1_P1
  DG58  USB11_TXP  OUT  = NC_CPU1_USB3_USB11_TXP
  DG59  VSS_DG59  POWER  = GND
  DG60  VSS_DG60  POWER  = GND
  DG61  VSS_DG61  POWER  = GND
  DG62  VSS_DG62  POWER  = GND
  DG63  VSS_DG63  POWER  = GND
  DG64  VDDIO_DG64  POWER  = PVDDIO_P1
  DG65  VSS_DG65  POWER  = GND
  DG66  VSS_DG66  POWER  = GND
  DG67  VSS_DG67  POWER  = GND
  DG68  VSS_DG68  POWER  = GND
  DG69  VSS_DG69  POWER  = GND
  DG70  VSS_DG70  POWER  = GND
  DG71  VDDIO_DG71  POWER  = PVDDIO_P1
  DG72  PCC1_L  IN  = FM_P1_PCC1_N
  DG73  SVT1  IN  = SVID_PVDDCR_CPU1_P1_SVTO
  DG74  VSS_DG74  POWER  = GND
  DG75  VSS_DG75  POWER  = GND
  DH3  VDD_11_S3_SENSE  POWER  = VSENSE_PVDD11_S3_P1_DP
  DH4  AGPIO7  BI  = NC
  DH5  VSS_DH5  POWER  = GND
  DH6  \sys_reset_l||agpio1\  BI  = RST_CPU1_SYS_N
  DH7  \pwr_btn_l||agpio0\  BI  = NC_CPU1_PWR_BTN_N
  DH8  RTC_LDO_SELECT  IN  = GND
  DH9  RTCCLK  BI  = CLK_CPU1_RTCCLK
  DH10  SP5R4  OUT  = CPU1_SP5R4
  DH11  VSS_DH11  POWER  = GND
  DH12  \i2c4_sda||hp_sda||ubm_sda||agpio14\  BI  = NC
  DH13  TEST4_CCD13  TRI  = NC
  DH14  TEST5_CCD13  TRI  = NC
  DH15  \agpio116||clk_req12_l\  BI  = FM_CPU1_BMC_RST_N
  DH16  \agpio115||clk_req11_l\  BI  = FM_BMC_TPM_PRES_N
  DH17  RSVD_DH17  TRI  = NC
  DH18  VSS_DH18  POWER  = GND
  DH19  VDDCR_CPU1_DH19  POWER  = PVDDCR_CPU1_P1
  DH20  VDDCR_CPU1_DH20  POWER  = PVDDCR_CPU1_P1
  DH21  RSVD_DH21  TRI  = NC
  DH22  VDDCR_CPU1_DH22  POWER  = PVDDCR_CPU1_P1
  DH23  VDDCR_CPU1_DH23  POWER  = PVDDCR_CPU1_P1
  DH24  \espi1_dat0||spi1_dat0||agpio131\  BI  = NC
  DH25  VDDCR_CPU1_DH25  POWER  = PVDDCR_CPU1_P1
  DH26  VDDCR_CPU1_DH26  POWER  = PVDDCR_CPU1_P1
  DH27  \spi_cs2_l||agpio126\  BI  = NC
  DH28  VDDCR_CPU1_DH28  POWER  = PVDDCR_CPU1_P1
  DH29  VDDCR_CPU1_DH29  POWER  = PVDDCR_CPU1_P1
  DH30  AGPIO104  BI  = NC
  DH31  VDDCR_CPU1_DH31  POWER  = PVDDCR_CPU1_P1
  DH32  VDDCR_CPU1_DH32  POWER  = PVDDCR_CPU1_P1
  DH33  \uart1_rxd||agpio141\  BI  = TP_CPU1_UART1_RX
  DH34  VDDCR_CPU1_DH34  POWER  = PVDDCR_CPU1_P1
  DH35  VDDCR_CPU1_DH35  POWER  = PVDDCR_CPU1_P1
  DH36  \pwrgd_out||agpio12\  BI  = CPU1_PWRGD_OUT
  DH37  VSS_DH37  POWER  = GND
  DH39  VSS_DH39  POWER  = GND
  DH40  \usb11_oc_l||agpio17\  BI  = NC_CPU1_USB11_OC_N
  DH41  VDDCR_CPU1_DH41  POWER  = PVDDCR_CPU1_P1
  DH42  VDDCR_CPU1_DH42  POWER  = PVDDCR_CPU1_P1
  DH43  VSS_DH43  POWER  = GND
  DH44  VDDCR_CPU1_DH44  POWER  = PVDDCR_CPU1_P1
  DH45  VDDCR_CPU1_DH45  POWER  = PVDDCR_CPU1_P1
  DH46  VSS_DH46  POWER  = GND
  DH47  VDDCR_CPU1_DH47  POWER  = PVDDCR_CPU1_P1
  DH48  VDDCR_CPU1_DH48  POWER  = PVDDCR_CPU1_P1
  DH49  VSS_DH49  POWER  = GND
  DH50  VDDCR_CPU1_DH50  POWER  = PVDDCR_CPU1_P1
  DH51  VDDCR_CPU1_DH51  POWER  = PVDDCR_CPU1_P1
  DH52  VSS_DH52  POWER  = GND
  DH53  VDDCR_CPU1_DH53  POWER  = PVDDCR_CPU1_P1
  DH54  VDDCR_CPU1_DH54  POWER  = PVDDCR_CPU1_P1
  DH55  VSS_DH55  POWER  = GND
  DH56  VDDCR_CPU1_DH56  POWER  = PVDDCR_CPU1_P1
  DH57  VDDCR_CPU1_DH57  POWER  = PVDDCR_CPU1_P1
  DH58  USB11_TXN  OUT  = NC_CPU1_USB3_USB11_TXN
  DH59  VSS_DH59  POWER  = GND
  DH60  USB11_DP  BI  = NC_CPU1_USB2_USB11_DP
  DH61  VSS_DH61  POWER  = GND
  DH62  USB11_RXN  IN  = NC_CPU1_USB3_USB11_RXN
  DH63  VSS_DH63  POWER  = GND
  DH64  VSS_DH64  POWER  = GND
  DH65  USB10_RXN  IN  = NC_CPU1_USB3_USB10_RXN
  DH66  VSS_DH66  POWER  = GND
  DH67  USB10_DN  BI  = NC_CPU1_USB2_USB10_DN
  DH68  VSS_DH68  POWER  = GND
  DH69  USB10_TXP  OUT  = NC_CPU1_USB3_USB10_TXP
  DH70  VSS_DH70  POWER  = GND
  DH71  SID  BI  = SMB_APML_CPU1_SDA
  DH72  SVD1  BI  = SVID_PVDDCR_CPU1_P1_SVD
  DH73  SP5R3  OUT  = CPU1_SP5R3
  DJ3  VSS_SENSE_C  POWER  = VSENSE_VSS_SENSE_C_P1
  DJ4  RSVD_DJ4  TRI  = NC
  DJ5  SLP_S3_L  OUT  = CPU1_SLP_S3_N
  DJ7  VSS_DJ7  POWER  = GND
  DJ8  PWR_GOOD  IN  = CPU1_PWR_GD_IN
  DJ9  THERMTRIP_L  OUT  = CPU1_THERMTRIP_N
  DJ10  \wake_l||agpio2\  BI  = IRQ_WAKE_N
  DJ11  \smerr_l||agpio24\  BI  = CPU1_SMERR_N
  DJ13  X32K_X2  IN  = XTAL_CPU1_X32K_X2
  DJ14  X32K_X1  IN  = XTAL_CPU1_X32K_X1
  DJ15  VSS_DJ15  POWER  = GND
  DJ16  X48M_X2  IN  = XTAL_CPU1_X48M_X2
  DJ17  X48M_X1  IN  = XTAL_CPU1_X48M_X1
  DJ19  VSS_DJ19  POWER  = GND
  DJ20  \i2c5_sda||bmc_sda||smbus1_sda||agpio20\  BI  = NC
  DJ21  \i2c5_scl||bmc_scl||smbus1_scl||agpio19\  BI  = NC
  DJ22  \espi0_alert_l||agpio108\  BI  = NC
  DJ23  \espi_cs1_l||agpio125\  BI  = NC
  DJ25  \agpio76||spi_tpm_cs_l\  BI  = NC
  DJ26  \espi_rstin_l||kbrst_l||agpio129\  BI  = NC
  DJ27  \espi_clk0||spi_clk0||agpio117\  BI  = SPI_CPU1_R_CLK
  DJ28  \espi0_dat2||spi0_dat2||agpio122\  BI  = NC
  DJ29  AGPIO88  BI  = NC
  DJ31  NMI_SYNC_FLOOD_L  IN  = CPU1_NMI_SYNC_FLOOD_N
  DJ32  \uart1_txd||agpio142\  BI  = NC
  DJ33  \uart0_cts_l||uart2_txd||agpio135\  BI  = TP_CPU1_UART0_CTS_N
  DJ34  \uart0_txd||agpio138\  BI  = TP_CPU1_UART0_TX
  DJ35  \genint_l||pm_intr_l||ubm_cprsnt_change_det_l||agpio89\  BI  = INT_CPU1_HP_UBM_N
  DJ41  GPP_CLK11P  OUT  = CLK_100M_CPU1_CLK11_R_DP
  DJ42  GPP_CLK11N  OUT  = CLK_100M_CPU1_CLK11_R_DN
  DJ43  VSS_DJ43  POWER  = GND
  DJ44  GPP_CLK12N  OUT  = CLK_100M_CPU1_CLK12_R_DN
  DJ45  GPP_CLK12P  OUT  = CLK_100M_CPU1_CLK12_R_DP
  DJ47  GPP_CLK14N  OUT  = NC
  DJ48  GPP_CLK14P  OUT  = NC
  DJ49  VSS_DJ49  POWER  = GND
  DJ50  GPP_CLK15N  OUT  = NC
  DJ51  GPP_CLK15P  OUT  = NC
  DJ53  GPP_CLK13P  OUT  = CLK_100M_CPU1_CLK13_R_DP
  DJ54  GPP_CLK13N  OUT  = CLK_100M_CPU1_CLK13_R_DN
  DJ55  SA0  IN  = CPU1_SA0
  DJ56  SA1  IN  = CPU1_SA1
  DJ57  TEST6_X3D7  OUT  = NC
  DJ59  VSS_DJ59  POWER  = GND
  DJ60  USB11_DN  BI  = NC_CPU1_USB2_USB11_DN
  DJ61  VSS_DJ61  POWER  = GND
  DJ62  USB11_RXP  IN  = NC_CPU1_USB3_USB11_RXP
  DJ63  VSS_DJ63  POWER  = GND
  DJ65  USB10_RXP  IN  = NC_CPU1_USB3_USB10_RXP
  DJ66  VSS_DJ66  POWER  = GND
  DJ67  USB10_DP  BI  = NC_CPU1_USB2_USB10_DP
  DJ68  VSS_DJ68  POWER  = GND
  DJ69  USB10_TXN  OUT  = NC_CPU1_USB3_USB10_TXN
  DJ71  SIC  OUT  = SMB_APML_CPU1_SCL
  DJ72  SVC1  OUT  = SVID_PVDDCR_CPU1_P1_SVC
  DJ73  VSS_DJ73  POWER  = GND
  E1  VSS_E1  POWER  = GND
  E2  MGA_DATA0  BI  = M_G_CPU1_SA_DQ<0>
  E3  VSS_E3  POWER  = GND
  E4  VDDCR_SOC_E4  POWER  = PVDDCR_SOC_P1
  E5  MKA_DATA0  BI  = M_K_CPU1_SA_DQ<0>
  E6  VSS_E6  POWER  = GND
  E7  VSS_E7  POWER  = GND
  E8  VSS_E8  POWER  = GND
  E9  MLA_DATA0  BI  = M_L_CPU1_SA_DQ<0>
  E10  VSS_E10  POWER  = GND
  E11  VDDCR_SOC_E11  POWER  = PVDDCR_SOC_P1
  E12  MHA_DATA0  BI  = M_H_CPU1_SA_DQ<0>
  E13  VSS_E13  POWER  = GND
  E14  VSS_E14  POWER  = GND
  E15  VSS_E15  POWER  = GND
  E16  MJA_DATA0  BI  = M_J_CPU1_SA_DQ<0>
  E17  VSS_E17  POWER  = GND
  E18  VSS_E18  POWER  = GND
  E19  MIA_DATA0  BI  = M_I_CPU1_SA_DQ<0>
  E20  VSS_E20  POWER  = GND
  E21  VSS_E21  POWER  = GND
  E22  VDDCR_CPU0_E22  POWER  = PVDDCR_CPU0_P1
  E23  \usb00_oc_l||agpio264\  BI  = NC_CPU1_USB00_OC_N
  E24  \usb01_oc_l||agpio265\  BI  = NC_CPU1_USB01_OC_N
  E25  VDDCR_CPU0_E25  POWER  = PVDDCR_CPU0_P1
  E26  USB00_RXN  IN  = NC_CPU1_USB3_USB00_RXN
  E27  USB00_RXP  IN  = NC_CPU1_USB3_USB00_RXP
  E28  VDDCR_CPU0_E28  POWER  = PVDDCR_CPU0_P1
  E29  USB01_TXN  OUT  = NC_CPU1_USB3_USB01_TXN
  E30  USB01_TXP  OUT  = NC_CPU1_USB3_USB01_TXP
  E31  VDDCR_CPU0_E31  POWER  = PVDDCR_CPU0_P1
  E32  TEST47_CCD3  TRI  = TP_CPU1_TEST47_CCD3
  E33  RSVD_E33  TRI  = NC
  E34  VDDCR_CPU0_E34  POWER  = PVDDCR_CPU0_P1
  E35  VDDCR_CPU0_E35  POWER  = PVDDCR_CPU0_P1
  E36  RSVD_E36  TRI  = NC
  E40  P5_RXP3  IN  = P3E_CPU1_P5_RX_DN<1>
  E41  P5_RXN3  IN  = P3E_CPU1_P5_RX_DP<1>
  E42  VDDCR_CPU0_E42  POWER  = PVDDCR_CPU0_P1
  E43  P5_RXP2  IN  = P3E_CPU1_P5_RX_DN<0>
  E44  P5_RXN2  IN  = P3E_CPU1_P5_RX_DP<0>
  E45  VDDCR_CPU0_E45  POWER  = PVDDCR_CPU0_P1
  E46  \wafl_rxp1||p5_rxp1\  IN  = WAFL_CPU0_TX0_CPU1_RX1_DP
  E47  \wafl_rxn1||p5_rxn1\  IN  = WAFL_CPU0_TX0_CPU1_RX1_DN
  E48  VDDCR_CPU0_E48  POWER  = PVDDCR_CPU0_P1
  E49  \wafl_rxp0||p5_rxp0\  IN  = NC
  E50  \wafl_rxn0||p5_rxn0\  IN  = NC
  E51  VDDCR_CPU0_E51  POWER  = PVDDCR_CPU0_P1
  E52  VSS_E52  POWER  = GND
  E53  VSS_E53  POWER  = GND
  E54  VDDCR_CPU0_E54  POWER  = PVDDCR_CPU0_P1
  E55  VSS_E55  POWER  = GND
  E56  VSS_E56  POWER  = GND
  E57  MCA_DATA0  BI  = M_C_CPU1_SA_DQ<0>
  E58  VSS_E58  POWER  = GND
  E59  VSS_E59  POWER  = GND
  E60  MDA_DATA0  BI  = M_D_CPU1_SA_DQ<0>
  E61  VSS_E61  POWER  = GND
  E62  VSS_E62  POWER  = GND
  E63  VSS_E63  POWER  = GND
  E64  MBA_DATA0  BI  = M_B_CPU1_SA_DQ<0>
  E65  VSS_E65  POWER  = GND
  E66  VSS_E66  POWER  = GND
  E67  MFA_DATA0  BI  = M_F_CPU1_SA_DQ<0>
  E68  VSS_E68  POWER  = GND
  E69  VSS_E69  POWER  = GND
  E70  VSS_E70  POWER  = GND
  E71  MEA_DATA0  BI  = M_E_CPU1_SA_DQ<0>
  E72  VSS_E72  POWER  = GND
  E73  VSS_E73  POWER  = GND
  E74  MAA_DATA0  BI  = M_A_CPU1_SA_DQ<0>
  E75  VSS_E75  POWER  = GND
  F2  MGA_DATA2  BI  = M_G_CPU1_SA_DQ<2>
  F3  VSS_F3  POWER  = GND
  F4  MGA_DATA1  BI  = M_G_CPU1_SA_DQ<1>
  F5  VSS_F5  POWER  = GND
  F6  MKA_DATA2  BI  = M_K_CPU1_SA_DQ<2>
  F7  MKA_DATA1  BI  = M_K_CPU1_SA_DQ<1>
  F8  VSS_F8  POWER  = GND
  F9  MLA_DATA2  BI  = M_L_CPU1_SA_DQ<2>
  F10  VSS_F10  POWER  = GND
  F11  MLA_DATA1  BI  = M_L_CPU1_SA_DQ<1>
  F12  VSS_F12  POWER  = GND
  F13  MHA_DATA2  BI  = M_H_CPU1_SA_DQ<2>
  F14  MHA_DATA1  BI  = M_H_CPU1_SA_DQ<1>
  F15  VSS_F15  POWER  = GND
  F16  MJA_DATA2  BI  = M_J_CPU1_SA_DQ<2>
  F17  VSS_F17  POWER  = GND
  F18  MJA_DATA1  BI  = M_J_CPU1_SA_DQ<1>
  F19  VSS_F19  POWER  = GND
  F20  MIA_DATA2  BI  = M_I_CPU1_SA_DQ<2>
  F21  MIA_DATA1  BI  = M_I_CPU1_SA_DQ<1>
  F22  VDDCR_CPU0_F22  POWER  = PVDDCR_CPU0_P1
  F23  VSS_F23  POWER  = GND
  F24  VSS_F24  POWER  = GND
  F25  VDDCR_CPU0_F25  POWER  = PVDDCR_CPU0_P1
